(kicad_pcb
	(version 20260206)
	(generator "pcbnew")
	(generator_version "10.0")
	(general
		(thickness 1.6)
		(legacy_teardrops no)
	)
	(paper "A4")
	(title_block
		(title "03242023_DA0F0TMBIJ0_F0T_Motherboard_J_brd_V01_OCP.brd")
		(comment 1 "Grand Teton / footprint 1682 of 6105 (U1), pads 4216-4324 of 4677")
	)
	(layers
		(0 "F.Cu" signal "TOP")
		(4 "In1.Cu" signal "GND")
		(6 "In2.Cu" signal "IN1")
		(8 "In3.Cu" signal "GND1")
		(10 "In4.Cu" signal "IN2")
		(12 "In5.Cu" signal "GND2")
		(14 "In6.Cu" signal "IN3")
		(16 "In7.Cu" signal "GND3")
		(18 "In8.Cu" signal "VCC")
		(20 "In9.Cu" signal "VCC1")
		(22 "In10.Cu" signal "GND4")
		(24 "In11.Cu" signal "IN4")
		(26 "In12.Cu" signal "GND5")
		(28 "In13.Cu" signal "IN5")
		(30 "In14.Cu" signal "GND6")
		(32 "In15.Cu" signal "IN6")
		(34 "In16.Cu" signal "GND7")
		(2 "B.Cu" signal "BOTTOM")
		(9 "F.Adhes" user "F.Adhesive")
		(11 "B.Adhes" user "B.Adhesive")
		(13 "F.Paste" user "Package Geometry/Pastemask Top")
		(15 "B.Paste" user "Package Geometry/Pastemask Bottom")
		(5 "F.SilkS" user "Ref Des/Silkscreen Top")
		(7 "B.SilkS" user "Ref Des/Silkscreen Bottom")
		(1 "F.Mask" user "Board Geometry/Soldermask Top")
		(3 "B.Mask" user "Board Geometry/Soldermask Bottom")
		(17 "Dwgs.User" user "User.Drawings")
		(19 "Cmts.User" user "User.Comments")
		(21 "Eco1.User" user "User.Eco1")
		(23 "Eco2.User" user "User.Eco2")
		(25 "Edge.Cuts" user "Board Geometry/Outline")
		(27 "Margin" user)
		(31 "F.CrtYd" user "Package Geometry/Place Bound Top")
		(29 "B.CrtYd" user "Package Geometry/Place Bound Bottom")
		(35 "F.Fab" user "Ref Des/Assembly Top")
		(33 "B.Fab" user "Ref Des/Assembly Bottom")
	)
	(footprint ""
		(layer "F.Cu")
		(at 111.93018 -251.76988 90)
		(property "Reference" "U1"
			(at -74.913236 41.548812 0)
			(unlocked yes)
			(layer "F.SilkS")
			(effects
				(font
					(size 1.6002 1.1938)
					(thickness 0.1524)
				)
				(justify left)
			)
		)
		(property "Value" ""
			(at 0 0 90)
			(layer "F.Fab")
			(effects
				(font
					(size 1.27 1.27)
				)
			)
		)
		(duplicate_pad_numbers_are_jumpers no)
		(pad "K63" smd circle
			(at 14.635988 -22.735286 270)
			(size 0.4318 0.4318)
			(layers "F.Cu" "F.Mask" "F.Paste")
			(net "M_B_CPU1_SA_DQ<16>")
		)
		(pad "K65" smd circle
			(at 16.263874 -22.735286 270)
			(size 0.4318 0.4318)
			(layers "F.Cu" "F.Mask" "F.Paste")
			(net "M_A_CPU1_SA_DQ<13>")
		)
		(pad "K67" smd circle
			(at 17.89176 -22.735286 270)
			(size 0.4318 0.4318)
			(layers "F.Cu" "F.Mask" "F.Paste")
			(net "M_A_CPU1_SA_DQS_DP<1>")
		)
		(pad "K69" smd circle
			(at 19.519392 -22.735286 270)
			(size 0.4318 0.4318)
			(layers "F.Cu" "F.Mask" "F.Paste")
			(net "M_A_CPU1_SA_DQ<8>")
		)
		(pad "K71" smd circle
			(at 21.147278 -22.735286 270)
			(size 0.4318 0.4318)
			(layers "F.Cu" "F.Mask" "F.Paste")
			(net "M_B_CPU1_SA_DQ<5>")
		)
		(pad "K73" smd circle
			(at 22.77491 -22.735286 270)
			(size 0.4318 0.4318)
			(layers "F.Cu" "F.Mask" "F.Paste")
			(net "M_B_CPU1_SA_DQS_DP<0>")
		)
		(pad "K75" smd circle
			(at 24.402796 -22.735286 270)
			(size 0.4318 0.4318)
			(layers "F.Cu" "F.Mask" "F.Paste")
			(net "M_B_CPU1_SA_DQ<0>")
		)
		(pad "K77" smd circle
			(at 26.030682 -22.735286 270)
			(size 0.4318 0.4318)
			(layers "F.Cu" "F.Mask" "F.Paste")
			(net "GND")
		)
		(pad "K79" smd circle
			(at 27.658314 -22.735286 270)
			(size 0.4318 0.4318)
			(layers "F.Cu" "F.Mask" "F.Paste")
			(net "UPI_CPU0_CPU1_P2P2_DN<3>")
		)
		(pad "K81" smd circle
			(at 29.2862 -22.735286 270)
			(size 0.4318 0.4318)
			(layers "F.Cu" "F.Mask" "F.Paste")
			(net "UPI_CPU0_CPU1_P2P2_DP<5>")
		)
		(pad "K83" smd circle
			(at 30.914086 -22.735286 270)
			(size 0.4318 0.4318)
			(layers "F.Cu" "F.Mask" "F.Paste")
			(net "GND")
		)
		(pad "K85" smd circle
			(at 32.541718 -22.735286 270)
			(size 0.4318 0.4318)
			(layers "F.Cu" "F.Mask" "F.Paste")
			(net "GND")
		)
		(pad "K87" smd circle
			(at 34.169604 -22.735286 270)
			(size 0.4318 0.4318)
			(layers "F.Cu" "F.Mask" "F.Paste")
			(net "PVCCFA_EHV_FIVRA_CPU1")
		)
		(pad "K89" smd circle
			(at 35.797236 -22.735286 270)
			(size 0.4318 0.4318)
			(layers "F.Cu" "F.Mask" "F.Paste")
			(net "P5E_CPU1_PE4_RX_DP<0>")
		)
		(pad "L3" smd circle
			(at -35.797236 -22.375114 270)
			(size 0.4318 0.4318)
			(layers "F.Cu" "F.Mask" "F.Paste")
			(net "UPI_CPU1_CPU0_P0P1_DP<1>")
		)
		(pad "L5" smd circle
			(at -34.169604 -22.375114 270)
			(size 0.4318 0.4318)
			(layers "F.Cu" "F.Mask" "F.Paste")
			(net "GND")
		)
		(pad "L7" smd circle
			(at -32.541718 -22.375114 270)
			(size 0.4318 0.4318)
			(layers "F.Cu" "F.Mask" "F.Paste")
			(net "UPI_CPU0_CPU1_P1P0_DP<0>")
		)
		(pad "L9" smd circle
			(at -30.914086 -22.375114 270)
			(size 0.4318 0.4318)
			(layers "F.Cu" "F.Mask" "F.Paste")
			(net "GND")
		)
		(pad "L11" smd circle
			(at -29.2862 -22.375114 270)
			(size 0.4318 0.4318)
			(layers "F.Cu" "F.Mask" "F.Paste")
			(net "P5E_CPU1_PE0_RX_DP<0>")
		)
		(pad "L13" smd circle
			(at -27.658314 -22.375114 270)
			(size 0.4318 0.4318)
			(layers "F.Cu" "F.Mask" "F.Paste")
			(net "GND")
		)
		(pad "L15" smd circle
			(at -26.030682 -22.375114 270)
			(size 0.4318 0.4318)
			(layers "F.Cu" "F.Mask" "F.Paste")
			(net "GND")
		)
		(pad "L17" smd circle
			(at -24.402796 -22.375114 270)
			(size 0.4318 0.4318)
			(layers "F.Cu" "F.Mask" "F.Paste")
			(net "GND")
		)
		(pad "L19" smd circle
			(at -22.77491 -22.375114 270)
			(size 0.4318 0.4318)
			(layers "F.Cu" "F.Mask" "F.Paste")
			(net "GND")
		)
		(pad "L21" smd circle
			(at -21.147278 -22.375114 270)
			(size 0.4318 0.4318)
			(layers "F.Cu" "F.Mask" "F.Paste")
			(net "GND")
		)
		(pad "L23" smd circle
			(at -19.519392 -22.375114 270)
			(size 0.4318 0.4318)
			(layers "F.Cu" "F.Mask" "F.Paste")
			(net "GND")
		)
		(pad "L25" smd circle
			(at -17.89176 -22.375114 270)
			(size 0.4318 0.4318)
			(layers "F.Cu" "F.Mask" "F.Paste")
			(net "GND")
		)
		(pad "L27" smd circle
			(at -16.263874 -22.375114 270)
			(size 0.4318 0.4318)
			(layers "F.Cu" "F.Mask" "F.Paste")
			(net "GND")
		)
		(pad "L29" smd circle
			(at -14.635988 -22.375114 270)
			(size 0.4318 0.4318)
			(layers "F.Cu" "F.Mask" "F.Paste")
			(net "GND")
		)
		(pad "L31" smd circle
			(at -13.008356 -22.375114 270)
			(size 0.4318 0.4318)
			(layers "F.Cu" "F.Mask" "F.Paste")
			(net "GND")
		)
		(pad "L33" smd circle
			(at -11.380724 -22.375114 270)
			(size 0.4318 0.4318)
			(layers "F.Cu" "F.Mask" "F.Paste")
			(net "GND")
		)
		(pad "L35" smd circle
			(at -9.752838 -22.375114 270)
			(size 0.4318 0.4318)
			(layers "F.Cu" "F.Mask" "F.Paste")
			(net "GND")
		)
		(pad "L37" smd circle
			(at -8.124952 -22.375114 270)
			(size 0.4318 0.4318)
			(layers "F.Cu" "F.Mask" "F.Paste")
			(net "GND")
		)
		(pad "L39" smd circle
			(at -6.49732 -22.375114 270)
			(size 0.4318 0.4318)
			(layers "F.Cu" "F.Mask" "F.Paste")
			(net "GND")
		)
		(pad "L41" smd circle
			(at -4.869434 -22.375114 270)
			(size 0.4318 0.4318)
			(layers "F.Cu" "F.Mask" "F.Paste")
			(net "GND")
		)
		(pad "L43" smd circle
			(at -3.241802 -22.375114 270)
			(size 0.4318 0.4318)
			(layers "F.Cu" "F.Mask" "F.Paste")
			(net "GND")
		)
		(pad "L45" smd circle
			(at -1.613916 -22.375114 270)
			(size 0.4318 0.4318)
			(layers "F.Cu" "F.Mask" "F.Paste")
			(net "GND")
		)
		(pad "L48" smd circle
			(at 2.427732 -22.265386 270)
			(size 0.4318 0.4318)
			(layers "F.Cu" "F.Mask" "F.Paste")
			(net "GND")
		)
		(pad "L50" smd circle
			(at 4.055618 -22.265386 270)
			(size 0.4318 0.4318)
			(layers "F.Cu" "F.Mask" "F.Paste")
			(net "GND")
		)
		(pad "L52" smd circle
			(at 5.68325 -22.265386 270)
			(size 0.4318 0.4318)
			(layers "F.Cu" "F.Mask" "F.Paste")
			(net "GND")
		)
		(pad "L54" smd circle
			(at 7.311136 -22.265386 270)
			(size 0.4318 0.4318)
			(layers "F.Cu" "F.Mask" "F.Paste")
			(net "GND")
		)
		(pad "L56" smd circle
			(at 8.939022 -22.265386 270)
			(size 0.4318 0.4318)
			(layers "F.Cu" "F.Mask" "F.Paste")
			(net "GND")
		)
		(pad "L58" smd circle
			(at 10.566654 -22.265386 270)
			(size 0.4318 0.4318)
			(layers "F.Cu" "F.Mask" "F.Paste")
			(net "GND")
		)
		(pad "L60" smd circle
			(at 12.19454 -22.265386 270)
			(size 0.4318 0.4318)
			(layers "F.Cu" "F.Mask" "F.Paste")
			(net "GND")
		)
		(pad "L62" smd circle
			(at 13.822426 -22.265386 270)
			(size 0.4318 0.4318)
			(layers "F.Cu" "F.Mask" "F.Paste")
			(net "GND")
		)
		(pad "L64" smd circle
			(at 15.450058 -22.265386 270)
			(size 0.4318 0.4318)
			(layers "F.Cu" "F.Mask" "F.Paste")
			(net "GND")
		)
		(pad "L66" smd circle
			(at 17.07769 -22.265386 270)
			(size 0.4318 0.4318)
			(layers "F.Cu" "F.Mask" "F.Paste")
			(net "GND")
		)
		(pad "L68" smd circle
			(at 18.705576 -22.265386 270)
			(size 0.4318 0.4318)
			(layers "F.Cu" "F.Mask" "F.Paste")
			(net "GND")
		)
		(pad "L70" smd circle
			(at 20.333462 -22.265386 270)
			(size 0.4318 0.4318)
			(layers "F.Cu" "F.Mask" "F.Paste")
			(net "GND")
		)
		(pad "L72" smd circle
			(at 21.961094 -22.265386 270)
			(size 0.4318 0.4318)
			(layers "F.Cu" "F.Mask" "F.Paste")
			(net "GND")
		)
		(pad "L74" smd circle
			(at 23.58898 -22.265386 270)
			(size 0.4318 0.4318)
			(layers "F.Cu" "F.Mask" "F.Paste")
			(net "GND")
		)
		(pad "L76" smd circle
			(at 25.216612 -22.265386 270)
			(size 0.4318 0.4318)
			(layers "F.Cu" "F.Mask" "F.Paste")
			(net "GND")
		)
		(pad "L78" smd circle
			(at 26.844498 -22.265386 270)
			(size 0.4318 0.4318)
			(layers "F.Cu" "F.Mask" "F.Paste")
			(net "GND")
		)
		(pad "L80" smd circle
			(at 28.472384 -22.265386 270)
			(size 0.4318 0.4318)
			(layers "F.Cu" "F.Mask" "F.Paste")
			(net "UPI_CPU0_CPU1_P2P2_DN<5>")
		)
		(pad "L82" smd circle
			(at 30.100016 -22.265386 270)
			(size 0.4318 0.4318)
			(layers "F.Cu" "F.Mask" "F.Paste")
			(net "UPI_CPU0_CPU1_P2P2_DP<4>")
		)
		(pad "L84" smd circle
			(at 31.727902 -22.265386 270)
			(size 0.4318 0.4318)
			(layers "F.Cu" "F.Mask" "F.Paste")
			(net "PVCCFA_EHV_FIVRA_CPU1")
		)
		(pad "L86" smd circle
			(at 33.355534 -22.265386 270)
			(size 0.4318 0.4318)
			(layers "F.Cu" "F.Mask" "F.Paste")
			(net "P5E_CPU1_PE4_TX_DN<0>")
		)
		(pad "L88" smd circle
			(at 34.98342 -22.265386 270)
			(size 0.4318 0.4318)
			(layers "F.Cu" "F.Mask" "F.Paste")
			(net "GND")
		)
		(pad "L90" smd oval
			(at 36.611306 -22.265386)
			(size 0.381 0.4826)
			(drill
				(offset 0 -0.0508)
			)
			(layers "F.Cu" "F.Mask" "F.Paste")
			(net "GND")
		)
		(pad "M2" smd oval
			(at -36.611306 -21.905468 180)
			(size 0.381 0.4826)
			(drill
				(offset 0 -0.0508)
			)
			(layers "F.Cu" "F.Mask" "F.Paste")
			(net "UPI_CPU1_CPU0_P0P1_DN<1>")
		)
		(pad "M4" smd circle
			(at -34.98342 -21.905468 270)
			(size 0.4318 0.4318)
			(layers "F.Cu" "F.Mask" "F.Paste")
			(net "GND")
		)
		(pad "M6" smd circle
			(at -33.355534 -21.905468 270)
			(size 0.4318 0.4318)
			(layers "F.Cu" "F.Mask" "F.Paste")
			(net "UPI_CPU0_CPU1_P1P0_DP<1>")
		)
		(pad "M8" smd circle
			(at -31.727902 -21.905468 270)
			(size 0.4318 0.4318)
			(layers "F.Cu" "F.Mask" "F.Paste")
			(net "GND")
		)
		(pad "M10" smd circle
			(at -30.100016 -21.905468 270)
			(size 0.4318 0.4318)
			(layers "F.Cu" "F.Mask" "F.Paste")
			(net "P5E_CPU1_PE0_RX_DN<1>")
		)
		(pad "M12" smd circle
			(at -28.472384 -21.905468 270)
			(size 0.4318 0.4318)
			(layers "F.Cu" "F.Mask" "F.Paste")
			(net "GND")
		)
		(pad "M14" smd circle
			(at -26.844498 -21.905468 270)
			(size 0.4318 0.4318)
			(layers "F.Cu" "F.Mask" "F.Paste")
			(net "P5E_CPU1_PE0_TX_DP<0>")
		)
		(pad "M16" smd circle
			(at -25.216612 -21.905468 270)
			(size 0.4318 0.4318)
			(layers "F.Cu" "F.Mask" "F.Paste")
			(net "M_B_CPU1_SB_DQ<23>")
		)
		(pad "M18" smd circle
			(at -23.58898 -21.905468 270)
			(size 0.4318 0.4318)
			(layers "F.Cu" "F.Mask" "F.Paste")
			(net "M_B_CPU1_SB_DQS_DN<7>")
		)
		(pad "M20" smd circle
			(at -21.961094 -21.905468 270)
			(size 0.4318 0.4318)
			(layers "F.Cu" "F.Mask" "F.Paste")
			(net "M_B_CPU1_SB_DQ<18>")
		)
		(pad "M22" smd circle
			(at -20.333462 -21.905468 270)
			(size 0.4318 0.4318)
			(layers "F.Cu" "F.Mask" "F.Paste")
			(net "M_B_CPU1_SB_DQ<15>")
		)
		(pad "M24" smd circle
			(at -18.705576 -21.905468 270)
			(size 0.4318 0.4318)
			(layers "F.Cu" "F.Mask" "F.Paste")
			(net "M_B_CPU1_SB_DQS_DN<6>")
		)
		(pad "M26" smd circle
			(at -17.07769 -21.905468 270)
			(size 0.4318 0.4318)
			(layers "F.Cu" "F.Mask" "F.Paste")
			(net "M_B_CPU1_SB_DQ<10>")
		)
		(pad "M28" smd circle
			(at -15.450058 -21.905468 270)
			(size 0.4318 0.4318)
			(layers "F.Cu" "F.Mask" "F.Paste")
			(net "M_A_CPU1_SB_DQ<7>")
		)
		(pad "M30" smd circle
			(at -13.822426 -21.905468 270)
			(size 0.4318 0.4318)
			(layers "F.Cu" "F.Mask" "F.Paste")
			(net "M_A_CPU1_SB_DQS_DN<5>")
		)
		(pad "M32" smd circle
			(at -12.19454 -21.905468 270)
			(size 0.4318 0.4318)
			(layers "F.Cu" "F.Mask" "F.Paste")
			(net "M_A_CPU1_SB_DQ<2>")
		)
		(pad "M34" smd circle
			(at -10.566654 -21.905468 270)
			(size 0.4318 0.4318)
			(layers "F.Cu" "F.Mask" "F.Paste")
			(net "M_B_CPU1_SB_CB<3>")
		)
		(pad "M36" smd circle
			(at -8.939022 -21.905468 270)
			(size 0.4318 0.4318)
			(layers "F.Cu" "F.Mask" "F.Paste")
			(net "M_B_CPU1_SB_DQS_DP<4>")
		)
		(pad "M38" smd circle
			(at -7.311136 -21.905468 270)
			(size 0.4318 0.4318)
			(layers "F.Cu" "F.Mask" "F.Paste")
			(net "M_B_CPU1_SB_CB<6>")
		)
		(pad "M40" smd circle
			(at -5.68325 -21.905468 270)
			(size 0.4318 0.4318)
			(layers "F.Cu" "F.Mask" "F.Paste")
			(net "M_B_CPU1_SB_CS_N<3>")
		)
		(pad "M42" smd circle
			(at -4.055618 -21.905468 270)
			(size 0.4318 0.4318)
			(layers "F.Cu" "F.Mask" "F.Paste")
			(net "GND")
		)
		(pad "M44" smd circle
			(at -2.427732 -21.905468 270)
			(size 0.4318 0.4318)
			(layers "F.Cu" "F.Mask" "F.Paste")
			(net "M_B_CPU1_SB_CA<3>")
		)
		(pad "M47" smd circle
			(at 1.613916 -21.795486 270)
			(size 0.4318 0.4318)
			(layers "F.Cu" "F.Mask" "F.Paste")
			(net "M_B_CPU1_SA_CA<5>")
		)
		(pad "M49" smd circle
			(at 3.241802 -21.795486 270)
			(size 0.4318 0.4318)
			(layers "F.Cu" "F.Mask" "F.Paste")
			(net "GND")
		)
		(pad "M51" smd circle
			(at 4.869434 -21.795486 270)
			(size 0.4318 0.4318)
			(layers "F.Cu" "F.Mask" "F.Paste")
			(net "M_B_CPU1_SA_CS_N<2>")
		)
		(pad "M53" smd circle
			(at 6.49732 -21.795486 270)
			(size 0.4318 0.4318)
			(layers "F.Cu" "F.Mask" "F.Paste")
			(net "M_B_CPU1_SA_CB<7>")
		)
		(pad "M55" smd circle
			(at 8.124952 -21.795486 270)
			(size 0.4318 0.4318)
			(layers "F.Cu" "F.Mask" "F.Paste")
			(net "M_B_CPU1_SA_DQS_DN<9>")
		)
		(pad "M57" smd circle
			(at 9.752838 -21.795486 270)
			(size 0.4318 0.4318)
			(layers "F.Cu" "F.Mask" "F.Paste")
			(net "M_B_CPU1_SA_CB<2>")
		)
		(pad "M59" smd circle
			(at 11.380724 -21.795486 270)
			(size 0.4318 0.4318)
			(layers "F.Cu" "F.Mask" "F.Paste")
			(net "M_B_CPU1_SA_DQ<23>")
		)
		(pad "M61" smd circle
			(at 13.008356 -21.795486 270)
			(size 0.4318 0.4318)
			(layers "F.Cu" "F.Mask" "F.Paste")
			(net "M_B_CPU1_SA_DQS_DN<7>")
		)
		(pad "M63" smd circle
			(at 14.635988 -21.795486 270)
			(size 0.4318 0.4318)
			(layers "F.Cu" "F.Mask" "F.Paste")
			(net "M_B_CPU1_SA_DQ<18>")
		)
		(pad "M65" smd circle
			(at 16.263874 -21.795486 270)
			(size 0.4318 0.4318)
			(layers "F.Cu" "F.Mask" "F.Paste")
			(net "M_A_CPU1_SA_DQ<15>")
		)
		(pad "M67" smd circle
			(at 17.89176 -21.795486 270)
			(size 0.4318 0.4318)
			(layers "F.Cu" "F.Mask" "F.Paste")
			(net "M_A_CPU1_SA_DQS_DP<6>")
		)
		(pad "M69" smd circle
			(at 19.519392 -21.795486 270)
			(size 0.4318 0.4318)
			(layers "F.Cu" "F.Mask" "F.Paste")
			(net "M_A_CPU1_SA_DQ<10>")
		)
		(pad "M71" smd circle
			(at 21.147278 -21.795486 270)
			(size 0.4318 0.4318)
			(layers "F.Cu" "F.Mask" "F.Paste")
			(net "M_B_CPU1_SA_DQ<7>")
		)
		(pad "M73" smd circle
			(at 22.77491 -21.795486 270)
			(size 0.4318 0.4318)
			(layers "F.Cu" "F.Mask" "F.Paste")
			(net "M_B_CPU1_SA_DQS_DN<5>")
		)
		(pad "M75" smd circle
			(at 24.402796 -21.795486 270)
			(size 0.4318 0.4318)
			(layers "F.Cu" "F.Mask" "F.Paste")
			(net "M_B_CPU1_SA_DQ<2>")
		)
		(pad "M77" smd circle
			(at 26.030682 -21.795486 270)
			(size 0.4318 0.4318)
			(layers "F.Cu" "F.Mask" "F.Paste")
			(net "M_A_CPU1_SA_DQ<2>")
		)
		(pad "M79" smd circle
			(at 27.658314 -21.795486 270)
			(size 0.4318 0.4318)
			(layers "F.Cu" "F.Mask" "F.Paste")
			(net "UPI_CPU0_CPU1_P2P2_DP<3>")
		)
		(pad "M81" smd circle
			(at 29.2862 -21.795486 270)
			(size 0.4318 0.4318)
			(layers "F.Cu" "F.Mask" "F.Paste")
			(net "GND")
		)
		(pad "M83" smd circle
			(at 30.914086 -21.795486 270)
			(size 0.4318 0.4318)
			(layers "F.Cu" "F.Mask" "F.Paste")
			(net "GND")
		)
		(pad "M85" smd circle
			(at 32.541718 -21.795486 270)
			(size 0.4318 0.4318)
			(layers "F.Cu" "F.Mask" "F.Paste")
			(net "PVCCFA_EHV_FIVRA_CPU1")
		)
		(pad "M87" smd circle
			(at 34.169604 -21.795486 270)
			(size 0.4318 0.4318)
			(layers "F.Cu" "F.Mask" "F.Paste")
			(net "P5E_CPU1_PE4_TX_DP<0>")
		)
		(pad "M89" smd circle
			(at 35.797236 -21.795486 270)
			(size 0.4318 0.4318)
			(layers "F.Cu" "F.Mask" "F.Paste")
			(net "PVCCFA_EHV_FIVRA_CPU1")
		)
		(pad "N1" smd oval
			(at -37.425122 -21.435314 180)
			(size 0.381 0.4826)
			(drill
				(offset 0 -0.0508)
			)
			(layers "F.Cu" "F.Mask" "F.Paste")
			(net "UPI_CPU1_CPU0_P0P1_DN<2>")
		)
		(pad "N3" smd circle
			(at -35.797236 -21.435314 270)
			(size 0.4318 0.4318)
			(layers "F.Cu" "F.Mask" "F.Paste")
			(net "PVCCFA_EHV_CPU1")
		)
		(pad "N5" smd circle
			(at -34.169604 -21.435314 270)
			(size 0.4318 0.4318)
			(layers "F.Cu" "F.Mask" "F.Paste")
			(net "UPI_CPU0_CPU1_P1P0_DN<1>")
		)
		(pad "N7" smd circle
			(at -32.541718 -21.435314 270)
			(size 0.4318 0.4318)
			(layers "F.Cu" "F.Mask" "F.Paste")
			(net "PVCCFA_EHV_FIVRA_CPU1")
		)
		(pad "N9" smd circle
			(at -30.914086 -21.435314 270)
			(size 0.4318 0.4318)
			(layers "F.Cu" "F.Mask" "F.Paste")
			(net "P5E_CPU1_PE0_RX_DP<1>")
		)
		(pad "N11" smd circle
			(at -29.2862 -21.435314 270)
			(size 0.4318 0.4318)
			(layers "F.Cu" "F.Mask" "F.Paste")
			(net "PVCCFA_EHV_FIVRA_CPU1")
		)
		(pad "N13" smd circle
			(at -27.658314 -21.435314 270)
			(size 0.4318 0.4318)
			(layers "F.Cu" "F.Mask" "F.Paste")
			(net "P5E_CPU1_PE0_TX_DN<0>")
		)
	)
)
